FILE_TYPE = CONNECTIVITY;
{Allegro Design Entry HDL 16.6-p007 (v16-6-112F) 10/10/2012}
"PAGE_NUMBER" = 230;
0"NC";
1"GND\g";
2"GND\g";
3"GND\g";
4"GND\g";
5"GND\g";
6"GND\g";
7"GND\g";
8"GND\g";
9"PVTT_KLM\g";
10"P3V3\g";
11"GND\g";
12"PVTT_KLM\g";
13"P3V3\g";
14"PVDDQ_KLM\g";
15"GND\g";
16"VR_PVTT_KLM_SNS";
17"FM_PVTT_KLM_EN_R";
18"VSENSE_PVDDQ_KLM_VTT";
19"VR_PVTT_KLM_BIAS";
20"PWRGD_PVTT_KLM_CPU1_R";
21"PWRGD_PVTT_CPU1";
22"PWRGD_PVDDQ_KLM_R";
23"VR_PVTT_KLM_VREF";
%"GND"
"1","(-2025,-1350)","0","mstr_symbols","I1";
;
HDL_POWER"GND"
BODY_TYPE"PLUMBING"
CDS_LIB"mstr_symbols"
SIZE"1B"
VOLTAGE"0.0V";
"A\NAC"1;
%"CAP"
"1","(-1300,225)","0","mstr_discrete","I10";
;
PACK_TYPE"0603"
PART_NUMBER"E15431-003"
MATERIAL"X6S"
TOLERANCE"10%"
VOLTAGE"6.3V"
VALUE"4.7UF"
LOCATION"C4A7"
CDS_SEC"1"
CDS_LIB"mstr_discrete"
ROOM"VTT_KLM_PWR_VR"
CDS_LOCATION"C4A7"
SEC"1"
SEC_TYPE"0603";
"A"
$PN"1"18;
"B"
$PN"2"15;
%"GND"
"1","(-1200,525)","0","mstr_symbols","I11";
;
HDL_POWER"GND"
BODY_TYPE"PLUMBING"
VOLTAGE"0.0V"
CDS_LIB"mstr_symbols"
SIZE"1B";
"A\NAC"2;
%"CAP"
"1","(-1200,775)","0","mstr_discrete","I12";
;
PART_NUMBER"D97712-011"
TOLERANCE"10%"
VALUE"1.0UF"
MATERIAL"X6S"
VOLTAGE"16V"
PACK_TYPE"0402"
LOCATION"C4A8"
CDS_SEC"1"
CDS_LIB"mstr_discrete"
ROOM"VTT_KLM_PWR_VR"
CDS_LOCATION"C4A8"
SEC"1"
BOM_COST"MEM_VRD_VTT_KLM"
SEC_TYPE"0402";
"A"
$PN"1"19;
"B"
$PN"2"2;
%"RES"
"1","(-1525,1025)","0","mstr_discrete","I13";
;
PACK_TYPE"0402"
MATERIAL"CHIP"
WATTAGE"1/16W"
VALUE"0.0"
TOLERANCE"5%"
PART_NUMBER"G21497-005"
LOCATION"R6L8"
CDS_SEC"1"
CDS_LIB"mstr_discrete"
SEC_TYPE"0402"
BOM_COST"MEM_VRD_VTT_KLM"
CDS_LOCATION"R6L8"
SEC"1"
ROOM"VTT_KLM_PWR_VR";
"B"
$PN"2"19;
"A"
$PN"1"13;
%"GND"
"1","(350,-150)","0","mstr_symbols","I14";
;
HDL_POWER"GND"
BODY_TYPE"PLUMBING"
CDS_LIB"mstr_symbols"
VOLTAGE"0.0V"
SIZE"1B";
"A\NAC"3;
%"GND"
"1","(-1625,1375)","0","mstr_symbols","I15";
;
HDL_POWER"GND"
BODY_TYPE"PLUMBING"
BOM_COST"MEM_VRD_VTT_KLM"
ROOM"VTT_KLM_PWR_VR"
SIZE"1B"
CDS_LIB"mstr_symbols"
VOLTAGE"0.0V";
"A\NAC"4;
%"GND"
"1","(-1200,1375)","0","mstr_symbols","I16";
;
HDL_POWER"GND"
BODY_TYPE"PLUMBING"
BOM_COST"MEM_VRD_VTT_KLM"
ROOM"VTT_KLM_PWR_VR"
CDS_LIB"mstr_symbols"
VOLTAGE"0.0V"
SIZE"1B";
"A\NAC"5;
%"CAP"
"1","(-1200,1650)","0","mstr_discrete","I17";
;
LOCATION"C4A15"
PACK_TYPE"0603LF"
PART_NUMBER"E15431-001"
MATERIAL"X6S"
TOLERANCE"20%"
VOLTAGE"4V"
VALUE"10UF"
CDS_SEC"1"
CDS_LIB"mstr_discrete"
CDS_LOCATION"C4A15"
ROOM"VTT_KLM_PWR_VR"
SEC"1"
SEC_TYPE"0603LF"
BOM_COST"MEM_VRD_VTT_KLM";
"A"
$PN"1"14;
"B"
$PN"2"5;
%"GND"
"1","(675,-150)","0","mstr_symbols","I18";
;
HDL_POWER"GND"
BODY_TYPE"PLUMBING"
CDS_LIB"mstr_symbols"
SIZE"1B"
VOLTAGE"0.0V";
"A\NAC"6;
%"GND"
"1","(2325,-75)","0","mstr_symbols","I19";
;
HDL_POWER"GND"
BODY_TYPE"PLUMBING"
SIZE"1B"
CDS_LIB"mstr_symbols"
VOLTAGE"0.0V";
"A\NAC"7;
%"CAP"
"1","(-2025,-1125)","2","mstr_discrete","I2";
;
PART_NUMBER"A36096-046"
MATERIAL"EMPTY"
PACK_TYPE"0402LF"
LOCATION"C4A6"
TOLERANCE"10%"
VOLTAGE"50V"
VALUE"1000PF"
CDS_SEC"1"
CDS_LIB"mstr_discrete"
CDS_LOCATION"C4A6"
BOM_COST"MEM_VRD_VTT_KLM"
SEC_TYPE"0402LF"
SEC"1"
ROOM"VTT_KLM_PWR_VR";
"A"
$PN"1"17;
"B"
$PN"2"1;
%"CAP"
"1","(2325,300)","0","mstr_discrete","I20";
;
GROUP"PWR_MLCC_CAP"
PART_NUMBER"C95333-002"
PACK_TYPE"0805LF"
MATERIAL"X6S"
TOLERANCE"20%"
VALUE"22UF"
VOLTAGE"4V"
LOCATION"C4A13"
CDS_SEC"1"
CDS_LIB"mstr_discrete"
CDS_LOCATION"C4A13"
ROOM"VTT_KLM_PWR_VR"
SEC_TYPE"0805LF"
BOM_COST"MEM_VRD_VTT_KLM"
SEC"1";
"A"
$PN"1"12;
"B"
$PN"2"7;
%"RES"
"2","(1800,1250)","2","mstr_discrete","I21";
;
PACK_TYPE"0402"
PART_NUMBER"G21796-016"
MATERIAL"CHIP"
WATTAGE"1/16W"
TOLERANCE"1%"
LOCATION"R4A5"
VALUE"10.0K"
CDS_SEC"1"
SEC_TYPE"0402"
BOM_COST"MEM_VRD_VTT_KLM"
SEC"1"
CDS_LOCATION"R4A5"
ROOM"VTT_KLM_PWR_VR"
CDS_LIB"mstr_discrete";
"A"
$PN"1"10;
"B"
$PN"2"20;
%"GND"
"1","(2200,650)","0","mstr_symbols","I22";
;
HDL_POWER"GND"
BODY_TYPE"PLUMBING"
VOLTAGE"0.0V"
CDS_LIB"mstr_symbols"
SIZE"1B";
"A\NAC"8;
%"CAP"
"1","(2200,900)","2","mstr_discrete","I23";
;
PACK_TYPE"0402LF"
PART_NUMBER"A36096-046"
MATERIAL"X7R"
TOLERANCE"10%"
VOLTAGE"50V"
VALUE"1000PF"
LOCATION"C4A3"
CDS_SEC"1"
SEC"1"
CDS_LOCATION"C4A3"
SEC_TYPE"0402LF"
BOM_COST"MEM_VRD_VTT_KLM"
ROOM"VTT_KLM_PWR_VR"
CDS_LIB"mstr_discrete";
"A"
$PN"1"20;
"B"
$PN"2"8;
%"CAP_A"
"1","(1350,2675)","0","dev_discrete","I24";
;
VOLTAGE"4V"
TOLERANCE"20%"
MATERIAL"X5R"
PART_NUMBER"602433-106"
PACK_TYPE"0603V"
VALUE"47UF"
GROUP"PWR_MLCC_CAP"
LOCATION"C8M12"
CDS_LIB"dev_discrete"
CDS_LOCATION"C8M12"
CDS_SEC"1"
SEC_TYPE"0603V"
SEC"1";
"B"
$PN"2"11;
"A"
$PN"1"9;
%"PVTT_KLM"
"1","(1350,2950)","0","mstr_symbols","I25";
;
HDL_POWER"PVTT_KLM"
BODY_TYPE"PLUMBING"
VOLTAGE"0.6V"
CDS_LIB"mstr_symbols"
ROOM"VTT_KLM_PWR_VR"
BOM_COST"MEM_KLM_VTT_DEF";
"G\NAC"9;
%"P3V3"
"1","(1800,1550)","0","mstr_symbols","I26";
;
HDL_POWER"P3V3"
BODY_TYPE"PLUMBING"
SIZE"1B"
CDS_LIB"mstr_symbols"
VOLTAGE"3.3V";
"G\NAC"10;
%"GND"
"1","(1350,2350)","0","mstr_symbols","I27";
;
HDL_POWER"GND"
BODY_TYPE"PLUMBING"
SIZE"1B"
VOLTAGE"0.0V"
CDS_LIB"mstr_symbols"
ROOM"VTT_KLM_PWR_VR"
BOM_COST"MEM_KLM_VTT_DEF";
"A\NAC"11;
%"SHUNT"
"1","(3300,-700)","0","mstr_misc","I30";
;
PART_NUMBER"N_A"
LOCATION"SH8L1"
CDS_SEC"1"
CDS_LOCATION"SH8L1"
PIN_SHORT"A:B"
PACK_TYPE"SH0201"
MATERIAL"EMPTY"
CDS_LIB"mstr_misc"
SEC"1"
SEC_TYPE"SH0201";
"A"
$PN"1"16;
"B"
$PN"2"12;
%"RES"
"1","(2575,1100)","0","mstr_discrete","I32";
;
PACK_TYPE"0402"
MATERIAL"CHIP"
VALUE"33.2"
LOCATION"R4A4"
PART_NUMBER"G21796-074"
WATTAGE"1/16W"
TOLERANCE"1%"
CDS_SEC"1"
SEC_TYPE"0402"
SEC"1"
CDS_LIB"mstr_discrete"
CDS_LOCATION"R4A4";
"B"
$PN"2"21;
"A"
$PN"1"20;
%"PVTT_KLM"
"1","(3875,850)","0","mstr_symbols","I34";
;
HDL_POWER"PVTT_KLM"
BODY_TYPE"PLUMBING"
VOLTAGE"0.6V"
CDS_LIB"mstr_symbols";
"G\NAC"12;
%"CAP"
"1","(-1625,1625)","0","mstr_discrete","I35";
;
PART_NUMBER"E15431-001"
VALUE"10UF"
MATERIAL"X6S"
LOCATION"C6L5"
TOLERANCE"20%"
VOLTAGE"4V"
PACK_TYPE"0603LF"
CDS_SEC"1"
CDS_LOCATION"C6L5"
CDS_LIB"mstr_discrete"
ROOM"VTT_KLM_PWR_VR"
BOM_COST"MEM_VRD_VTT_KLM"
SEC_TYPE"0603LF"
SEC"1";
"A"
$PN"1"14;
"B"
$PN"2"4;
%"CAP"
"1","(675,125)","0","mstr_discrete","I36";
;
PART_NUMBER"D97712-011"
TOLERANCE"10%"
MATERIAL"X6S"
VALUE"1.0UF"
VOLTAGE"16V"
PACK_TYPE"0402"
LOCATION"C4A14"
CDS_SEC"1"
CDS_LIB"mstr_discrete"
CDS_LOCATION"C4A14"
SEC_TYPE"0402"
BOM_COST"MEM_VRD_VTT_KLM"
SEC"1"
ROOM"VTT_KLM_PWR_VR";
"A"
$PN"1"23;
"B"
$PN"2"6;
%"MIC5166"
"1","(-100,325)","0","mstr_vreg","I37";
;
LOCATION"EU4A2"
PART_NUMBER"H55101-001"
MATERIAL"IC"
CDS_SEC"1"
CDS_LOCATION"EU4A2"
ROOM"VTT_KLM_PWR_VR"
BOM_COST"MEM_VRD_VTT_KLM"
SEC_TYPE"DFN"
SEC"1"
PACK_TYPE"DFN"
CDS_LMAN_SYM_OUTLINE"-250,350,250,-350"
CDS_LIB"mstr_vreg";
"THPAD"
$PN"11"3;
"VTT"
$PN"9"12;
"PGND"
$PN"8"3;
"SNS"
$PN"6"16;
"VDDQ"
$PN"4"18;
"PG"
$PN"5"20;
"AGND"
$PN"3"3;
"BIAS"
$PN"2"19;
"VREF"
$PN"1"23;
"VIN"
$PN"10"14;
"EN"
$PN"7"17;
%"RES"
"1","(-2225,-600)","0","mstr_discrete","I4";
;
PACK_TYPE"0402"
VALUE"0.0"
TOLERANCE"5%"
LOCATION"R4A3"
PART_NUMBER"G21497-005"
MATERIAL"CHIP"
WATTAGE"1/16W"
CDS_SEC"1"
CDS_LIB"mstr_discrete"
ROOM"VTT_KLM_PWR_VR"
CDS_LOCATION"R4A3"
SEC"1"
BOM_COST"MEM_VRD_VTT_KLM"
SEC_TYPE"0402";
"B"
$PN"2"17;
"A"
$PN"1"22;
%"CAP"
"1","(1750,2675)","0","mstr_discrete","I41";
;
LOCATION"C8L3"
TOLERANCE"20%"
VOLTAGE"4V"
VALUE"100UF"
PART_NUMBER"602433-112"
PACK_TYPE"0805"
GROUP"PWR_MLCC_CAP"
NEW_MATERIAL"X6S"
NEW_PN"078.1071T.M002"
CDS_LOCATION"C8L3"
CDS_SEC"1"
CDS_LIB"mstr_discrete"
BOM_COST"MEM_VRD_PVDDQ_CD"
ROOM"VDDQ_ABC_PWR_VR"
SEC_TYPE"0805"
SEC"1"
MATERIAL"X5R";
"A"
$PN"1"9;
"B"
$PN"2"11;
%"CAP"
"1","(2150,2675)","0","mstr_discrete","I42";
;
VALUE"100UF"
VOLTAGE"4V"
TOLERANCE"20%"
LOCATION"C8L4"
PACK_TYPE"0805"
GROUP"PWR_MLCC_CAP"
PART_NUMBER"602433-112"
NEW_MATERIAL"X6S"
NEW_PN"078.1071T.M002"
CDS_LOCATION"C8L4"
MATERIAL"X5R"
SEC"1"
SEC_TYPE"0805"
ROOM"VDDQ_ABC_PWR_VR"
BOM_COST"MEM_VRD_PVDDQ_CD"
CDS_LIB"mstr_discrete"
CDS_SEC"1";
"A"
$PN"1"9;
"B"
$PN"2"11;
%"CAP"
"1","(3125,325)","0","mstr_discrete","I43";
;
NEW_PN"078.1071T.M002"
GROUP"PWR_MLCC_CAP"
NEW_MATERIAL"X6S"
PART_NUMBER"602433-112"
PACK_TYPE"0805"
LOCATION"C6W13"
TOLERANCE"20%"
VOLTAGE"4V"
VALUE"100UF"
CDS_LOCATION"C6W13"
CDS_SEC"1"
CDS_LIB"mstr_discrete"
BOM_COST"MEM_VRD_PVDDQ_CD"
ROOM"VDDQ_ABC_PWR_VR"
SEC_TYPE"0805"
SEC"1"
MATERIAL"X5R";
"A"
$PN"1"12;
"B"
$PN"2"7;
%"RES"
"2","(-1975,-75)","2","mstr_discrete","I5";
;
PACK_TYPE"0402"
PART_NUMBER"G21796-021"
MATERIAL"EMPTY"
WATTAGE"1/16W"
TOLERANCE"1%"
VALUE"1.0M"
LOCATION"R6L5"
CDS_SEC"1"
CDS_LIB"mstr_discrete"
BOM_COST"MEM_VRD_VTT_KLM"
SEC_TYPE"0402"
SEC"1"
CDS_LOCATION"R6L5"
ROOM"VTT_KLM_PWR_VR";
"A"
$PN"1"13;
"B"
$PN"2"17;
%"RES"
"2","(-2350,825)","1","mstr_discrete","I6";
;
MATERIAL"CHIP"
PART_NUMBER"G21497-005"
TOLERANCE"5%"
VALUE"0.0"
WATTAGE"1/16W"
LOCATION"R6L6"
PACK_TYPE"0402"
CDS_SEC"1"
CDS_LIB"mstr_discrete"
SEC_TYPE"0402"
BOM_COST"MEM_VRD_VTT_KLM"
CDS_LOCATION"R6L6"
NO_XNET_CONNECTION"1"
SEC"1"
ROOM"VTT_KLM_PWR_VR";
"A"
$PN"1"14;
"B"
$PN"2"18;
%"P3V3"
"1","(-2050,1325)","0","mstr_symbols","I7";
;
HDL_POWER"P3V3"
BODY_TYPE"PLUMBING"
VOLTAGE"3.3V"
CDS_LIB"mstr_symbols"
SIZE"1B";
"G\NAC"13;
%"PVDDQ_KLM"
"1","(-3100,2050)","0","mstr_symbols","I8";
;
HDL_POWER"PVDDQ_KLM"
BODY_TYPE"PLUMBING"
CDS_LIB"mstr_symbols"
VOLTAGE"1.2V";
"G\NAC"14;
%"GND"
"1","(-1300,25)","0","mstr_symbols","I9";
;
HDL_POWER"GND"
BODY_TYPE"PLUMBING"
SIZE"1B"
VOLTAGE"0.0V"
CDS_LIB"mstr_symbols";
"A\NAC"15;
END.
